# T6G (Grand Teton) — schematic netlist excerpt (pin names and nets, part order shuffled) for the footprints in the layout excerpt that follows; sources: Cadence DE-HDL packaged netlist, KiCad conversion of 04192023_DAF0TMB3IC0_F0TG_MB_C_brd_V02_OCP.brd

R3268  Q_RES  68K 1% EMPTY  pkg 0402LF  page 111 : A = FM_P2E_EQA1 ; B = GND
R1035  Q_RES  4.7K 5% CHIP  pkg 0201LF  page 287 : A = TEST2_RT_CPU0_P1 ; B = GND
H8  HOLE  EMPTY  pkg TH  page 230 : \1\ = GND
C347  Q_CAP  0.1UF 25V 10% X7R  pkg 0402  page 259 : A = P1V8_AUX ; B = GND

(kicad_pcb
	(version 20260206)
	(generator "pcbnew")
	(generator_version "10.0")
	(general
		(thickness 1.6)
		(legacy_teardrops no)
	)
	(paper "A4")
	(title_block
		(title "04192023_DAF0TMB3IC0_F0TG_MB_C_brd_V02_OCP.brd")
		(comment 1 "Grand Teton / footprints 4300-4303 of 8354")
	)
	(layers
		(0 "F.Cu" signal "TOP")
		(4 "In1.Cu" signal "GND")
		(6 "In2.Cu" signal "IN1")
		(8 "In3.Cu" signal "GND1")
		(10 "In4.Cu" signal "IN2")
		(12 "In5.Cu" signal "GND2")
		(14 "In6.Cu" signal "IN3")
		(16 "In7.Cu" signal "GND3")
		(18 "In8.Cu" signal "VCC")
		(20 "In9.Cu" signal "VCC1")
		(22 "In10.Cu" signal "GND4")
		(24 "In11.Cu" signal "IN4")
		(26 "In12.Cu" signal "GND5")
		(28 "In13.Cu" signal "IN5")
		(30 "In14.Cu" signal "GND6")
		(32 "In15.Cu" signal "IN6")
		(34 "In16.Cu" signal "GND7")
		(2 "B.Cu" signal "BOTTOM")
		(9 "F.Adhes" user "F.Adhesive")
		(11 "B.Adhes" user "B.Adhesive")
		(13 "F.Paste" user "Package Geometry/Pastemask Top")
		(15 "B.Paste" user "Package Geometry/Pastemask Bottom")
		(5 "F.SilkS" user "Ref Des/Silkscreen Top")
		(7 "B.SilkS" user "Ref Des/Silkscreen Bottom")
		(1 "F.Mask" user "Board Geometry/Soldermask Top")
		(3 "B.Mask" user "Board Geometry/Soldermask Bottom")
		(17 "Dwgs.User" user "User.Drawings")
		(19 "Cmts.User" user "User.Comments")
		(21 "Eco1.User" user "User.Eco1")
		(23 "Eco2.User" user "User.Eco2")
		(25 "Edge.Cuts" user "Board Geometry/Outline")
		(27 "Margin" user)
		(31 "F.CrtYd" user "Package Geometry/Place Bound Top")
		(29 "B.CrtYd" user "Package Geometry/Place Bound Bottom")
		(35 "F.Fab" user "Ref Des/Assembly Top")
		(33 "B.Fab" user "Ref Des/Assembly Bottom")
	)
	(footprint ""
		(layer "F.Cu")
		(at 331.793342 -392.1252)
		(property "Reference" "R1035"
			(at 0 0 0)
			(layer "F.SilkS")
			(hide yes)
			(effects
				(font
					(size 1.27 1.27)
				)
			)
		)
		(property "Value" ""
			(at 0 0 0)
			(layer "F.Fab")
			(effects
				(font
					(size 1.27 1.27)
				)
			)
		)
		(duplicate_pad_numbers_are_jumpers no)
		(fp_line
			(start -0.32512 -0.175006)
			(end 0.32512 -0.175006)
			(stroke
				(width 0.1)
				(type default)
			)
			(layer "F.Fab")
		)
		(fp_line
			(start -0.32512 0.175006)
			(end -0.32512 -0.175006)
			(stroke
				(width 0.1)
				(type default)
			)
			(layer "F.Fab")
		)
		(fp_line
			(start 0.32512 -0.175006)
			(end 0.32512 0.175006)
			(stroke
				(width 0.1)
				(type default)
			)
			(layer "F.Fab")
		)
		(fp_line
			(start 0.32512 0.175006)
			(end -0.32512 0.175006)
			(stroke
				(width 0.1)
				(type default)
			)
			(layer "F.Fab")
		)
		(pad "1" smd rect
			(at -0.2667 0)
			(size 0.3048 0.381)
			(layers "F.Cu" "F.Mask" "F.Paste")
			(net "TEST2_RT_CPU0_P1")
		)
		(pad "2" smd rect
			(at 0.2667 0 180)
			(size 0.3048 0.381)
			(layers "F.Cu" "F.Mask" "F.Paste")
			(net "GND")
		)
	)
	(footprint ""
		(layer "F.Cu")
		(at 98.344736 -120.52173 -90)
		(property "Reference" "C347"
			(at 0 0 270)
			(layer "F.SilkS")
			(hide yes)
			(effects
				(font
					(size 1.27 1.27)
				)
			)
		)
		(property "Value" ""
			(at 0 0 270)
			(layer "F.Fab")
			(effects
				(font
					(size 1.27 1.27)
				)
			)
		)
		(duplicate_pad_numbers_are_jumpers no)
		(fp_line
			(start -0.7874 0.4064)
			(end -0.7874 -0.4064)
			(stroke
				(width 0.1524)
				(type default)
			)
			(layer "F.SilkS")
		)
		(fp_line
			(start 0.7874 0.4064)
			(end -0.7874 0.4064)
			(stroke
				(width 0.1524)
				(type default)
			)
			(layer "F.SilkS")
		)
		(fp_line
			(start -0.7874 -0.4064)
			(end 0.7874 -0.4064)
			(stroke
				(width 0.1524)
				(type default)
			)
			(layer "F.SilkS")
		)
		(fp_line
			(start 0.7874 -0.4064)
			(end 0.7874 0.4064)
			(stroke
				(width 0.1524)
				(type default)
			)
			(layer "F.SilkS")
		)
		(fp_line
			(start -0.67945 0.3048)
			(end -0.67945 -0.305054)
			(stroke
				(width 0.1)
				(type default)
			)
			(layer "F.Fab")
		)
		(fp_line
			(start -0.12065 0.3048)
			(end -0.67945 0.3048)
			(stroke
				(width 0.1)
				(type default)
			)
			(layer "F.Fab")
		)
		(fp_line
			(start 0.120396 0.3048)
			(end 0.120396 0.2794)
			(stroke
				(width 0.1)
				(type default)
			)
			(layer "F.Fab")
		)
		(fp_line
			(start 0.67945 0.3048)
			(end 0.120396 0.3048)
			(stroke
				(width 0.1)
				(type default)
			)
			(layer "F.Fab")
		)
		(fp_line
			(start -0.12065 0.2794)
			(end -0.12065 0.3048)
			(stroke
				(width 0.1)
				(type default)
			)
			(layer "F.Fab")
		)
		(fp_line
			(start 0.120396 0.2794)
			(end -0.12065 0.2794)
			(stroke
				(width 0.1)
				(type default)
			)
			(layer "F.Fab")
		)
		(fp_line
			(start -0.12065 -0.2794)
			(end 0.12065 -0.2794)
			(stroke
				(width 0.1)
				(type default)
			)
			(layer "F.Fab")
		)
		(fp_line
			(start 0.12065 -0.2794)
			(end 0.12065 -0.3048)
			(stroke
				(width 0.1)
				(type default)
			)
			(layer "F.Fab")
		)
		(fp_line
			(start 0.12065 -0.3048)
			(end 0.67945 -0.3048)
			(stroke
				(width 0.1)
				(type default)
			)
			(layer "F.Fab")
		)
		(fp_line
			(start 0.67945 -0.3048)
			(end 0.67945 0.3048)
			(stroke
				(width 0.1)
				(type default)
			)
			(layer "F.Fab")
		)
		(fp_line
			(start -0.67945 -0.305054)
			(end -0.12065 -0.305054)
			(stroke
				(width 0.1)
				(type default)
			)
			(layer "F.Fab")
		)
		(fp_line
			(start -0.12065 -0.305054)
			(end -0.12065 -0.2794)
			(stroke
				(width 0.1)
				(type default)
			)
			(layer "F.Fab")
		)
		(pad "1" smd circle
			(at -0.40005 0 270)
			(size 0 0)
			(layers "F.Cu" "F.Mask" "F.Paste")
			(net "P1V8_AUX")
		)
		(pad "2" smd circle
			(at 0.40005 0 270)
			(size 0 0)
			(layers "F.Cu" "F.Mask" "F.Paste")
			(net "GND")
		)
	)
	(footprint ""
		(layer "F.Cu")
		(at 221.899988 -290.89985)
		(property "Reference" "H8"
			(at -1.960118 -4.20751 0)
			(unlocked yes)
			(layer "F.SilkS")
			(effects
				(font
					(size 0.7874 0.5842)
					(thickness 0.1524)
				)
				(justify left)
			)
		)
		(property "Value" ""
			(at 0 0 0)
			(layer "F.Fab")
			(effects
				(font
					(size 1.27 1.27)
				)
			)
		)
		(duplicate_pad_numbers_are_jumpers no)
		(pad "1" thru_hole circle
			(at 0 0)
			(size 6.1976 6.1976)
			(drill 3.7338)
			(layers "*.Cu" "*.Mask")
			(remove_unused_layers no)
			(net "GND")
			(clearance -0.9779)
			(padstack
				(mode front_inner_back)
				(layer "Inner"
					(shape circle)
					(size 5.5372 5.5372)
					(clearance -0.6477)
				)
				(layer "B.Cu"
					(shape circle)
					(size 6.1976 6.1976)
					(clearance -0.9779)
				)
			)
		)
	)
	(footprint ""
		(layer "F.Cu")
		(at 29.553662 -419.249098 -90)
		(property "Reference" "R3268"
			(at 0 0 270)
			(layer "F.SilkS")
			(hide yes)
			(effects
				(font
					(size 1.27 1.27)
				)
			)
		)
		(property "Value" ""
			(at 0 0 270)
			(layer "F.Fab")
			(effects
				(font
					(size 1.27 1.27)
				)
			)
		)
		(duplicate_pad_numbers_are_jumpers no)
		(fp_line
			(start -0.7874 0.4064)
			(end -0.7874 -0.4064)
			(stroke
				(width 0.1524)
				(type default)
			)
			(layer "F.SilkS")
		)
		(fp_line
			(start 0.7874 0.4064)
			(end -0.7874 0.4064)
			(stroke
				(width 0.1524)
				(type default)
			)
			(layer "F.SilkS")
		)
		(fp_line
			(start -0.7874 -0.4064)
			(end 0.7874 -0.4064)
			(stroke
				(width 0.1524)
				(type default)
			)
			(layer "F.SilkS")
		)
		(fp_line
			(start 0.7874 -0.4064)
			(end 0.7874 0.4064)
			(stroke
				(width 0.1524)
				(type default)
			)
			(layer "F.SilkS")
		)
		(fp_line
			(start -0.67945 0.3048)
			(end -0.67945 -0.305054)
			(stroke
				(width 0.1)
				(type default)
			)
			(layer "F.Fab")
		)
		(fp_line
			(start -0.12065 0.3048)
			(end -0.67945 0.3048)
			(stroke
				(width 0.1)
				(type default)
			)
			(layer "F.Fab")
		)
		(fp_line
			(start 0.120396 0.3048)
			(end 0.120396 0.2794)
			(stroke
				(width 0.1)
				(type default)
			)
			(layer "F.Fab")
		)
		(fp_line
			(start 0.67945 0.3048)
			(end 0.120396 0.3048)
			(stroke
				(width 0.1)
				(type default)
			)
			(layer "F.Fab")
		)
		(fp_line
			(start -0.12065 0.2794)
			(end -0.12065 0.3048)
			(stroke
				(width 0.1)
				(type default)
			)
			(layer "F.Fab")
		)
		(fp_line
			(start 0.120396 0.2794)
			(end -0.12065 0.2794)
			(stroke
				(width 0.1)
				(type default)
			)
			(layer "F.Fab")
		)
		(fp_line
			(start -0.12065 -0.2794)
			(end 0.12065 -0.2794)
			(stroke
				(width 0.1)
				(type default)
			)
			(layer "F.Fab")
		)
		(fp_line
			(start 0.12065 -0.2794)
			(end 0.12065 -0.3048)
			(stroke
				(width 0.1)
				(type default)
			)
			(layer "F.Fab")
		)
		(fp_line
			(start 0.12065 -0.3048)
			(end 0.67945 -0.3048)
			(stroke
				(width 0.1)
				(type default)
			)
			(layer "F.Fab")
		)
		(fp_line
			(start 0.67945 -0.3048)
			(end 0.67945 0.3048)
			(stroke
				(width 0.1)
				(type default)
			)
			(layer "F.Fab")
		)
		(fp_line
			(start -0.67945 -0.305054)
			(end -0.12065 -0.305054)
			(stroke
				(width 0.1)
				(type default)
			)
			(layer "F.Fab")
		)
		(fp_line
			(start -0.12065 -0.305054)
			(end -0.12065 -0.2794)
			(stroke
				(width 0.1)
				(type default)
			)
			(layer "F.Fab")
		)
		(pad "1" smd circle
			(at -0.40005 0 270)
			(size 0 0)
			(layers "F.Cu" "F.Mask" "F.Paste")
			(net "FM_P2E_EQA1")
		)
		(pad "2" smd circle
			(at 0.40005 0 270)
			(size 0 0)
			(layers "F.Cu" "F.Mask" "F.Paste")
			(net "GND")
		)
	)
)
